# BASEBOARD_FAB2 (Tioga Pass) — schematic netlist excerpt (pin names and nets, part order shuffled) for the footprints in the layout excerpt that follows; sources: Cadence DE-HDL packaged netlist, KiCad conversion of Wiwynn_Tioga_Pass_MB.brd

CF10  SC22P50V2JN-4GP  5%  pkg SMD-BCG  page 206 : \1\ = VR_PVCCIN_CPU1_AIREF4 ; \2\ = ISENSE_PVCCIN_CPU1_PH4_IMON
C4C17  CAP  0.220UF 16V 10% X7R  pkg 0402  page 204 : A = VR_PVCCIN_CPU0_PH5_BOOT ; B = VR_PVCCIN_CPU0_PH5_PHASE
RF10  RES  1.0K 0.1% CHIP  pkg 0402  page 206 : A = VR_PVCCIN_CPU1_AIREF4 ; B = ISENSE_PVCCIN_CPU1_PH4_IMON

(kicad_pcb
	(version 20260206)
	(generator "pcbnew")
	(generator_version "10.0")
	(general
		(thickness 1.6)
		(legacy_teardrops no)
	)
	(paper "A4")
	(title_block
		(title "Wiwynn_Tioga_Pass_MB.brd")
		(comment 1 "Tioga Pass / footprints 200-202 of 4770")
	)
	(layers
		(0 "F.Cu" signal "TOP")
		(4 "In1.Cu" signal "L2GND")
		(6 "In2.Cu" signal "L3")
		(8 "In3.Cu" signal "L4GND")
		(10 "In4.Cu" signal "L5")
		(12 "In5.Cu" signal "L6GND")
		(14 "In6.Cu" signal "L7VCC")
		(16 "In7.Cu" signal "L8VCC")
		(18 "In8.Cu" signal "L9GND")
		(20 "In9.Cu" signal "L10")
		(22 "In10.Cu" signal "L11GND")
		(24 "In11.Cu" signal "L12")
		(26 "In12.Cu" signal "L13GND")
		(2 "B.Cu" signal "BOTTOM")
		(9 "F.Adhes" user "F.Adhesive")
		(11 "B.Adhes" user "B.Adhesive")
		(13 "F.Paste" user "Package Geometry/Pastemask Top")
		(15 "B.Paste" user "Package Geometry/Pastemask Bottom")
		(5 "F.SilkS" user "Ref Des/Silkscreen Top")
		(7 "B.SilkS" user "Ref Des/Silkscreen Bottom")
		(1 "F.Mask" user "Board Geometry/Soldermask Top")
		(3 "B.Mask" user "Board Geometry/Soldermask Bottom")
		(17 "Dwgs.User" user "User.Drawings")
		(19 "Cmts.User" user "User.Comments")
		(21 "Eco1.User" user "User.Eco1")
		(23 "Eco2.User" user "User.Eco2")
		(25 "Edge.Cuts" user "Board Geometry/Outline")
		(27 "Margin" user)
		(31 "F.CrtYd" user "Package Geometry/Place Bound Top")
		(29 "B.CrtYd" user "Package Geometry/Place Bound Bottom")
		(35 "F.Fab" user "Ref Des/Assembly Top")
		(33 "B.Fab" user "Ref Des/Assembly Bottom")
	)
	(footprint ""
		(layer "F.Cu")
		(at 25.02408 -91.96832 180)
		(property "Reference" "CF10"
			(at 0 0 180)
			(layer "F.SilkS")
			(hide yes)
			(effects
				(font
					(size 1.27 1.27)
				)
			)
		)
		(property "Value" "*"
			(at 1.1811 -2.8194 180)
			(unlocked yes)
			(layer "F.Fab")
			(hide yes)
			(effects
				(font
					(size 1.27 1.016)
					(thickness 0.1524)
				)
			)
		)
		(property "Device Type" "SC22P50V2JN-4GP_SMD-BCG-SC22P5A"
			(at 1.1811 -4.3434 180)
			(unlocked yes)
			(layer "F.Fab")
			(hide yes)
			(effects
				(font
					(size 1.27 1.016)
					(thickness 0.1524)
				)
			)
		)
		(duplicate_pad_numbers_are_jumpers no)
		(fp_rect
			(start -0.4318 0.9525)
			(end 0.4318 -0.9525)
			(stroke
				(width 0)
				(type default)
			)
			(fill no)
			(layer "F.CrtYd")
		)
		(fp_rect
			(start -0.4318 0.9525)
			(end 0.4318 -0.9525)
			(stroke
				(width 0)
				(type default)
			)
			(fill no)
			(layer "F.Fab")
		)
		(pad "1" smd custom
			(at 0 -0.4445 180)
			(size 0.1524 0.1524)
			(layers "F.Cu" "F.Mask" "F.Paste")
			(net "VR_PVCCIN_CPU1_AIREF4")
			(options
				(clearance outline)
				(anchor circle)
			)
			(primitives
				(gr_poly
					(pts
						(arc
							(start 0.3048 -0.2032)
							(mid 0.275042 -0.275042)
							(end 0.2032 -0.3048)
						)
						(arc
							(start -0.2032 -0.3048)
							(mid -0.275042 -0.275042)
							(end -0.3048 -0.2032)
						)
						(arc
							(start -0.3048 0.2032)
							(mid -0.275042 0.275042)
							(end -0.2032 0.3048)
						)
						(arc
							(start 0.2032 0.3048)
							(mid 0.275042 0.275042)
							(end 0.3048 0.2032)
						)
					)
					(width 0)
					(fill yes)
				)
			)
		)
		(pad "2" smd custom
			(at 0 0.4445 180)
			(size 0.1524 0.1524)
			(layers "F.Cu" "F.Mask" "F.Paste")
			(net "ISENSE_PVCCIN_CPU1_PH4_IMON")
			(options
				(clearance outline)
				(anchor circle)
			)
			(primitives
				(gr_poly
					(pts
						(arc
							(start 0.3048 -0.2032)
							(mid 0.275042 -0.275042)
							(end 0.2032 -0.3048)
						)
						(arc
							(start -0.2032 -0.3048)
							(mid -0.275042 -0.275042)
							(end -0.3048 -0.2032)
						)
						(arc
							(start -0.3048 0.2032)
							(mid -0.275042 0.275042)
							(end -0.2032 0.3048)
						)
						(arc
							(start 0.2032 0.3048)
							(mid 0.275042 0.275042)
							(end 0.3048 0.2032)
						)
					)
					(width 0)
					(fill yes)
				)
			)
		)
	)
	(footprint ""
		(layer "F.Cu")
		(at 193.8782 -91.3892 90)
		(property "Reference" "C4C17"
			(at 0 0 90)
			(layer "F.SilkS")
			(hide yes)
			(effects
				(font
					(size 1.27 1.27)
				)
			)
		)
		(property "Value" ""
			(at 0 0 90)
			(layer "F.Fab")
			(effects
				(font
					(size 1.27 1.27)
				)
			)
		)
		(duplicate_pad_numbers_are_jumpers no)
		(fp_rect
			(start -0.3048 0.9906)
			(end 0.3048 -0.1016)
			(stroke
				(width 0)
				(type default)
			)
			(fill no)
			(layer "F.CrtYd")
		)
		(fp_line
			(start 0.3048 -0.1016)
			(end -0.3048 -0.1016)
			(stroke
				(width 0.1)
				(type default)
			)
			(layer "F.Fab")
		)
		(fp_line
			(start -0.3048 -0.1016)
			(end -0.3048 0.9906)
			(stroke
				(width 0.1)
				(type default)
			)
			(layer "F.Fab")
		)
		(fp_line
			(start 0.3048 0.9906)
			(end 0.3048 -0.1016)
			(stroke
				(width 0.1)
				(type default)
			)
			(layer "F.Fab")
		)
		(fp_line
			(start -0.3048 0.9906)
			(end 0.3048 0.9906)
			(stroke
				(width 0.1)
				(type default)
			)
			(layer "F.Fab")
		)
		(pad "1" smd rect
			(at 0 0 90)
			(size 0.508 0.508)
			(layers "F.Cu" "F.Mask" "F.Paste")
			(net "VR_PVCCIN_CPU0_PH5_BOOT")
		)
		(pad "2" smd rect
			(at 0 0.889 90)
			(size 0.508 0.508)
			(layers "F.Cu" "F.Mask" "F.Paste")
			(net "VR_PVCCIN_CPU0_PH5_PHASE")
		)
		(zone
			(layer "F.Cu")
			(hatch none 0.5)
			(connect_pads
				(clearance 0)
			)
			(min_thickness 0.25)
			(keepout
				(tracks allowed)
				(vias not_allowed)
				(pads allowed)
				(copperpour not_allowed)
				(footprints allowed)
			)
			(placement
				(enabled no)
				(sheetname "")
			)
			(fill
				(thermal_gap 0.5)
				(thermal_bridge_width 0.5)
				(island_removal_mode 0)
			)
			(polygon
				(pts
					(xy 194.5132 -91.1352) (xy 194.5132 -91.6432) (xy 194.1322 -91.6432) (xy 194.1322 -91.1352)
				)
			)
		)
		(zone
			(layer "F.Cu")
			(hatch none 0.5)
			(connect_pads
				(clearance 0)
			)
			(min_thickness 0.25)
			(keepout
				(tracks not_allowed)
				(vias allowed)
				(pads allowed)
				(copperpour not_allowed)
				(footprints allowed)
			)
			(placement
				(enabled no)
				(sheetname "")
			)
			(fill
				(thermal_gap 0.5)
				(thermal_bridge_width 0.5)
				(island_removal_mode 0)
			)
			(polygon
				(pts
					(xy 194.5132 -91.1352) (xy 194.5132 -91.6432) (xy 194.1322 -91.6432) (xy 194.1322 -91.1352)
				)
			)
		)
	)
	(footprint ""
		(layer "F.Cu")
		(at 24.03602 -91.36888 180)
		(property "Reference" "RF10"
			(at -0.8382 -0.67818 180)
			(unlocked yes)
			(layer "F.SilkS")
			(effects
				(font
					(size 0.4064 0.254)
					(thickness 0.1524)
				)
				(justify left)
			)
		)
		(property "Value" ""
			(at 0 0 180)
			(layer "F.Fab")
			(effects
				(font
					(size 1.27 1.27)
				)
			)
		)
		(duplicate_pad_numbers_are_jumpers no)
		(fp_poly
			(pts
				(xy -0.2794 -0.1016) (xy 0.2794 -0.1016) (xy 0.2794 0.9906) (xy -0.2794 0.9906)
			)
			(stroke
				(width 0)
				(type default)
			)
			(fill no)
			(layer "F.CrtYd")
		)
		(fp_line
			(start 0.2794 0.9906)
			(end 0.2794 -0.1016)
			(stroke
				(width 0.1)
				(type default)
			)
			(layer "F.Fab")
		)
		(fp_line
			(start 0.2794 -0.1016)
			(end -0.2794 -0.1016)
			(stroke
				(width 0.1)
				(type default)
			)
			(layer "F.Fab")
		)
		(fp_line
			(start -0.2794 0.9906)
			(end 0.2794 0.9906)
			(stroke
				(width 0.1)
				(type default)
			)
			(layer "F.Fab")
		)
		(fp_line
			(start -0.2794 -0.1016)
			(end -0.2794 0.9906)
			(stroke
				(width 0.1)
				(type default)
			)
			(layer "F.Fab")
		)
		(pad "1" smd rect
			(at 0 0 180)
			(size 0.508 0.508)
			(layers "F.Cu" "F.Mask" "F.Paste")
			(net "VR_PVCCIN_CPU1_AIREF4")
		)
		(pad "2" smd rect
			(at 0 0.889 180)
			(size 0.508 0.508)
			(layers "F.Cu" "F.Mask" "F.Paste")
			(net "ISENSE_PVCCIN_CPU1_PH4_IMON")
		)
		(zone
			(layer "F.Cu")
			(hatch none 0.5)
			(connect_pads
				(clearance 0)
			)
			(min_thickness 0.25)
			(keepout
				(tracks not_allowed)
				(vias allowed)
				(pads allowed)
				(copperpour not_allowed)
				(footprints allowed)
			)
			(placement
				(enabled no)
				(sheetname "")
			)
			(fill
				(thermal_gap 0.5)
				(thermal_bridge_width 0.5)
				(island_removal_mode 0)
			)
			(polygon
				(pts
					(xy 24.29002 -92.00388) (xy 23.78202 -92.00388) (xy 23.78202 -91.62288) (xy 24.29002 -91.62288)
				)
			)
		)
		(zone
			(layer "F.Cu")
			(hatch none 0.5)
			(connect_pads
				(clearance 0)
			)
			(min_thickness 0.25)
			(keepout
				(tracks allowed)
				(vias not_allowed)
				(pads allowed)
				(copperpour not_allowed)
				(footprints allowed)
			)
			(placement
				(enabled no)
				(sheetname "")
			)
			(fill
				(thermal_gap 0.5)
				(thermal_bridge_width 0.5)
				(island_removal_mode 0)
			)
			(polygon
				(pts
					(xy 24.29002 -91.62288) (xy 23.78202 -91.62288) (xy 23.78202 -92.00388) (xy 24.29002 -92.00388)
				)
			)
		)
	)
)
